# T6G (Grand Teton) — schematic netlist excerpt (pin names and nets, part order shuffled) for the footprints in the layout excerpt that follows; sources: Cadence DE-HDL packaged netlist, KiCad conversion of 04192023_DAF0TMB3IC0_F0TG_MB_C_brd_V02_OCP.brd

R817  Q_RES  0 5% CHIP  pkg 0402LF  page 164 : A = UART_CPU0_UART0_RX ; B = UART_CPU0_UART0_R_RX
C915  Q_CAP_DIFFBUS  DIFF BUS_0.22UF 6.3V 20% X6S  pkg C0201  page 63 : \1\ = P5E_CPU0_P0_TX_C_DP<9> ; \2\ = P5E_CPU0_P0_TX_DP<9>
R6740  Q_RES  0 5% CHIP  pkg 0402LF  page 81 : A = RST_RT_CPU1_P1_PERST_R_N ; B = RST_RT_CPU1_P1_PERST_R2_N

(kicad_pcb
	(version 20260206)
	(generator "pcbnew")
	(generator_version "10.0")
	(general
		(thickness 1.6)
		(legacy_teardrops no)
	)
	(paper "A4")
	(title_block
		(title "04192023_DAF0TMB3IC0_F0TG_MB_C_brd_V02_OCP.brd")
		(comment 1 "Grand Teton / footprints 3980-3982 of 8354")
	)
	(layers
		(0 "F.Cu" signal "TOP")
		(4 "In1.Cu" signal "GND")
		(6 "In2.Cu" signal "IN1")
		(8 "In3.Cu" signal "GND1")
		(10 "In4.Cu" signal "IN2")
		(12 "In5.Cu" signal "GND2")
		(14 "In6.Cu" signal "IN3")
		(16 "In7.Cu" signal "GND3")
		(18 "In8.Cu" signal "VCC")
		(20 "In9.Cu" signal "VCC1")
		(22 "In10.Cu" signal "GND4")
		(24 "In11.Cu" signal "IN4")
		(26 "In12.Cu" signal "GND5")
		(28 "In13.Cu" signal "IN5")
		(30 "In14.Cu" signal "GND6")
		(32 "In15.Cu" signal "IN6")
		(34 "In16.Cu" signal "GND7")
		(2 "B.Cu" signal "BOTTOM")
		(9 "F.Adhes" user "F.Adhesive")
		(11 "B.Adhes" user "B.Adhesive")
		(13 "F.Paste" user "Package Geometry/Pastemask Top")
		(15 "B.Paste" user "Package Geometry/Pastemask Bottom")
		(5 "F.SilkS" user "Ref Des/Silkscreen Top")
		(7 "B.SilkS" user "Ref Des/Silkscreen Bottom")
		(1 "F.Mask" user "Board Geometry/Soldermask Top")
		(3 "B.Mask" user "Board Geometry/Soldermask Bottom")
		(17 "Dwgs.User" user "User.Drawings")
		(19 "Cmts.User" user "User.Comments")
		(21 "Eco1.User" user "User.Eco1")
		(23 "Eco2.User" user "User.Eco2")
		(25 "Edge.Cuts" user "Board Geometry/Outline")
		(27 "Margin" user)
		(31 "F.CrtYd" user "Package Geometry/Place Bound Top")
		(29 "B.CrtYd" user "Package Geometry/Place Bound Bottom")
		(35 "F.Fab" user "Ref Des/Assembly Top")
		(33 "B.Fab" user "Ref Des/Assembly Bottom")
	)
	(footprint ""
		(layer "F.Cu")
		(at 314.305696 -378.95403 -90)
		(property "Reference" "C915"
			(at 0 0 270)
			(layer "F.SilkS")
			(hide yes)
			(effects
				(font
					(size 1.27 1.27)
				)
			)
		)
		(property "Value" ""
			(at 0 0 270)
			(layer "F.Fab")
			(effects
				(font
					(size 1.27 1.27)
				)
			)
		)
		(duplicate_pad_numbers_are_jumpers no)
		(fp_line
			(start -0.299974 0.150114)
			(end -0.299974 -0.150114)
			(stroke
				(width 0.1)
				(type default)
			)
			(layer "F.Fab")
		)
		(fp_line
			(start 0.299974 0.150114)
			(end -0.299974 0.150114)
			(stroke
				(width 0.1)
				(type default)
			)
			(layer "F.Fab")
		)
		(fp_line
			(start -0.299974 -0.150114)
			(end 0.299974 -0.150114)
			(stroke
				(width 0.1)
				(type default)
			)
			(layer "F.Fab")
		)
		(fp_line
			(start 0.299974 -0.150114)
			(end 0.299974 0.150114)
			(stroke
				(width 0.1)
				(type default)
			)
			(layer "F.Fab")
		)
		(pad "1" smd rect
			(at -0.2667 0 270)
			(size 0.3048 0.381)
			(layers "F.Cu" "F.Mask" "F.Paste")
			(net "P5E_CPU0_P0_TX_C_DP<9>")
		)
		(pad "2" smd rect
			(at 0.2667 0 270)
			(size 0.3048 0.381)
			(layers "F.Cu" "F.Mask" "F.Paste")
			(net "P5E_CPU0_P0_TX_DP<9>")
		)
	)
	(footprint ""
		(layer "F.Cu")
		(at 180.457856 -139.947142 -90)
		(property "Reference" "R6740"
			(at 0 0 270)
			(layer "F.SilkS")
			(hide yes)
			(effects
				(font
					(size 1.27 1.27)
				)
			)
		)
		(property "Value" ""
			(at 0 0 270)
			(layer "F.Fab")
			(effects
				(font
					(size 1.27 1.27)
				)
			)
		)
		(duplicate_pad_numbers_are_jumpers no)
		(fp_line
			(start -0.7874 0.4064)
			(end -0.7874 -0.4064)
			(stroke
				(width 0.1524)
				(type default)
			)
			(layer "F.SilkS")
		)
		(fp_line
			(start 0.7874 0.4064)
			(end -0.7874 0.4064)
			(stroke
				(width 0.1524)
				(type default)
			)
			(layer "F.SilkS")
		)
		(fp_line
			(start -0.7874 -0.4064)
			(end 0.7874 -0.4064)
			(stroke
				(width 0.1524)
				(type default)
			)
			(layer "F.SilkS")
		)
		(fp_line
			(start 0.7874 -0.4064)
			(end 0.7874 0.4064)
			(stroke
				(width 0.1524)
				(type default)
			)
			(layer "F.SilkS")
		)
		(fp_line
			(start -0.67945 0.3048)
			(end -0.67945 -0.305054)
			(stroke
				(width 0.1)
				(type default)
			)
			(layer "F.Fab")
		)
		(fp_line
			(start -0.12065 0.3048)
			(end -0.67945 0.3048)
			(stroke
				(width 0.1)
				(type default)
			)
			(layer "F.Fab")
		)
		(fp_line
			(start 0.120396 0.3048)
			(end 0.120396 0.2794)
			(stroke
				(width 0.1)
				(type default)
			)
			(layer "F.Fab")
		)
		(fp_line
			(start 0.67945 0.3048)
			(end 0.120396 0.3048)
			(stroke
				(width 0.1)
				(type default)
			)
			(layer "F.Fab")
		)
		(fp_line
			(start -0.12065 0.2794)
			(end -0.12065 0.3048)
			(stroke
				(width 0.1)
				(type default)
			)
			(layer "F.Fab")
		)
		(fp_line
			(start 0.120396 0.2794)
			(end -0.12065 0.2794)
			(stroke
				(width 0.1)
				(type default)
			)
			(layer "F.Fab")
		)
		(fp_line
			(start -0.12065 -0.2794)
			(end 0.12065 -0.2794)
			(stroke
				(width 0.1)
				(type default)
			)
			(layer "F.Fab")
		)
		(fp_line
			(start 0.12065 -0.2794)
			(end 0.12065 -0.3048)
			(stroke
				(width 0.1)
				(type default)
			)
			(layer "F.Fab")
		)
		(fp_line
			(start 0.12065 -0.3048)
			(end 0.67945 -0.3048)
			(stroke
				(width 0.1)
				(type default)
			)
			(layer "F.Fab")
		)
		(fp_line
			(start 0.67945 -0.3048)
			(end 0.67945 0.3048)
			(stroke
				(width 0.1)
				(type default)
			)
			(layer "F.Fab")
		)
		(fp_line
			(start -0.67945 -0.305054)
			(end -0.12065 -0.305054)
			(stroke
				(width 0.1)
				(type default)
			)
			(layer "F.Fab")
		)
		(fp_line
			(start -0.12065 -0.305054)
			(end -0.12065 -0.2794)
			(stroke
				(width 0.1)
				(type default)
			)
			(layer "F.Fab")
		)
		(pad "1" smd circle
			(at -0.40005 0 270)
			(size 0 0)
			(layers "F.Cu" "F.Mask" "F.Paste")
			(net "RST_RT_CPU1_P1_PERST_R_N")
		)
		(pad "2" smd circle
			(at 0.40005 0 270)
			(size 0 0)
			(layers "F.Cu" "F.Mask" "F.Paste")
			(net "RST_RT_CPU1_P1_PERST_R2_N")
		)
	)
	(footprint ""
		(layer "F.Cu")
		(at 365.701326 -43.235118 -90)
		(property "Reference" "R817"
			(at 0 0 270)
			(layer "F.SilkS")
			(hide yes)
			(effects
				(font
					(size 1.27 1.27)
				)
			)
		)
		(property "Value" ""
			(at 0 0 270)
			(layer "F.Fab")
			(effects
				(font
					(size 1.27 1.27)
				)
			)
		)
		(duplicate_pad_numbers_are_jumpers no)
		(fp_line
			(start -0.7874 0.4064)
			(end -0.7874 -0.4064)
			(stroke
				(width 0.1524)
				(type default)
			)
			(layer "F.SilkS")
		)
		(fp_line
			(start 0.7874 0.4064)
			(end -0.7874 0.4064)
			(stroke
				(width 0.1524)
				(type default)
			)
			(layer "F.SilkS")
		)
		(fp_line
			(start -0.7874 -0.4064)
			(end 0.7874 -0.4064)
			(stroke
				(width 0.1524)
				(type default)
			)
			(layer "F.SilkS")
		)
		(fp_line
			(start 0.7874 -0.4064)
			(end 0.7874 0.4064)
			(stroke
				(width 0.1524)
				(type default)
			)
			(layer "F.SilkS")
		)
		(fp_line
			(start -0.67945 0.3048)
			(end -0.67945 -0.305054)
			(stroke
				(width 0.1)
				(type default)
			)
			(layer "F.Fab")
		)
		(fp_line
			(start -0.12065 0.3048)
			(end -0.67945 0.3048)
			(stroke
				(width 0.1)
				(type default)
			)
			(layer "F.Fab")
		)
		(fp_line
			(start 0.120396 0.3048)
			(end 0.120396 0.2794)
			(stroke
				(width 0.1)
				(type default)
			)
			(layer "F.Fab")
		)
		(fp_line
			(start 0.67945 0.3048)
			(end 0.120396 0.3048)
			(stroke
				(width 0.1)
				(type default)
			)
			(layer "F.Fab")
		)
		(fp_line
			(start -0.12065 0.2794)
			(end -0.12065 0.3048)
			(stroke
				(width 0.1)
				(type default)
			)
			(layer "F.Fab")
		)
		(fp_line
			(start 0.120396 0.2794)
			(end -0.12065 0.2794)
			(stroke
				(width 0.1)
				(type default)
			)
			(layer "F.Fab")
		)
		(fp_line
			(start -0.12065 -0.2794)
			(end 0.12065 -0.2794)
			(stroke
				(width 0.1)
				(type default)
			)
			(layer "F.Fab")
		)
		(fp_line
			(start 0.12065 -0.2794)
			(end 0.12065 -0.3048)
			(stroke
				(width 0.1)
				(type default)
			)
			(layer "F.Fab")
		)
		(fp_line
			(start 0.12065 -0.3048)
			(end 0.67945 -0.3048)
			(stroke
				(width 0.1)
				(type default)
			)
			(layer "F.Fab")
		)
		(fp_line
			(start 0.67945 -0.3048)
			(end 0.67945 0.3048)
			(stroke
				(width 0.1)
				(type default)
			)
			(layer "F.Fab")
		)
		(fp_line
			(start -0.67945 -0.305054)
			(end -0.12065 -0.305054)
			(stroke
				(width 0.1)
				(type default)
			)
			(layer "F.Fab")
		)
		(fp_line
			(start -0.12065 -0.305054)
			(end -0.12065 -0.2794)
			(stroke
				(width 0.1)
				(type default)
			)
			(layer "F.Fab")
		)
		(pad "1" smd circle
			(at -0.40005 0 270)
			(size 0 0)
			(layers "F.Cu" "F.Mask" "F.Paste")
			(net "UART_CPU0_UART0_RX")
		)
		(pad "2" smd circle
			(at 0.40005 0 270)
			(size 0 0)
			(layers "F.Cu" "F.Mask" "F.Paste")
			(net "UART_CPU0_UART0_R_RX")
		)
	)
)
